(kicad_pcb
	(version 20260206)
	(generator "pcbnew")
	(generator_version "10.0")
	(general
		(thickness 1.6)
		(legacy_teardrops no)
	)
	(paper "A4")
	(title_block
		(title "04192023_DAF0TMB3IC0_F0TG_MB_C_brd_V02_OCP.brd")
		(comment 1 "Grand Teton / footprints 3599-3605 of 8354")
	)
	(layers
		(0 "F.Cu" signal "TOP")
		(4 "In1.Cu" signal "GND")
		(6 "In2.Cu" signal "IN1")
		(8 "In3.Cu" signal "GND1")
		(10 "In4.Cu" signal "IN2")
		(12 "In5.Cu" signal "GND2")
		(14 "In6.Cu" signal "IN3")
		(16 "In7.Cu" signal "GND3")
		(18 "In8.Cu" signal "VCC")
		(20 "In9.Cu" signal "VCC1")
		(22 "In10.Cu" signal "GND4")
		(24 "In11.Cu" signal "IN4")
		(26 "In12.Cu" signal "GND5")
		(28 "In13.Cu" signal "IN5")
		(30 "In14.Cu" signal "GND6")
		(32 "In15.Cu" signal "IN6")
		(34 "In16.Cu" signal "GND7")
		(2 "B.Cu" signal "BOTTOM")
		(9 "F.Adhes" user "F.Adhesive")
		(11 "B.Adhes" user "B.Adhesive")
		(13 "F.Paste" user "Package Geometry/Pastemask Top")
		(15 "B.Paste" user "Package Geometry/Pastemask Bottom")
		(5 "F.SilkS" user "Ref Des/Silkscreen Top")
		(7 "B.SilkS" user "Ref Des/Silkscreen Bottom")
		(1 "F.Mask" user "Board Geometry/Soldermask Top")
		(3 "B.Mask" user "Board Geometry/Soldermask Bottom")
		(17 "Dwgs.User" user "User.Drawings")
		(19 "Cmts.User" user "User.Comments")
		(21 "Eco1.User" user "User.Eco1")
		(23 "Eco2.User" user "User.Eco2")
		(25 "Edge.Cuts" user "Board Geometry/Outline")
		(27 "Margin" user)
		(31 "F.CrtYd" user "Package Geometry/Place Bound Top")
		(29 "B.CrtYd" user "Package Geometry/Place Bound Bottom")
		(35 "F.Fab" user "Ref Des/Assembly Top")
		(33 "B.Fab" user "Ref Des/Assembly Bottom")
	)
	(footprint ""
		(layer "F.Cu")
		(at 138.426952 -59.83224 180)
		(property "Reference" "R1728"
			(at 0 0 180)
			(layer "F.SilkS")
			(hide yes)
			(effects
				(font
					(size 1.27 1.27)
				)
			)
		)
		(property "Value" ""
			(at 0 0 180)
			(layer "F.Fab")
			(effects
				(font
					(size 1.27 1.27)
				)
			)
		)
		(duplicate_pad_numbers_are_jumpers no)
		(fp_line
			(start 0.7874 0.4064)
			(end -0.7874 0.4064)
			(stroke
				(width 0.1524)
				(type default)
			)
			(layer "F.SilkS")
		)
		(fp_line
			(start 0.7874 -0.4064)
			(end 0.7874 0.4064)
			(stroke
				(width 0.1524)
				(type default)
			)
			(layer "F.SilkS")
		)
		(fp_line
			(start -0.7874 0.4064)
			(end -0.7874 -0.4064)
			(stroke
				(width 0.1524)
				(type default)
			)
			(layer "F.SilkS")
		)
		(fp_line
			(start -0.7874 -0.4064)
			(end 0.7874 -0.4064)
			(stroke
				(width 0.1524)
				(type default)
			)
			(layer "F.SilkS")
		)
		(fp_line
			(start 0.67945 0.3048)
			(end 0.120396 0.3048)
			(stroke
				(width 0.1)
				(type default)
			)
			(layer "F.Fab")
		)
		(fp_line
			(start 0.67945 -0.3048)
			(end 0.67945 0.3048)
			(stroke
				(width 0.1)
				(type default)
			)
			(layer "F.Fab")
		)
		(fp_line
			(start 0.12065 -0.2794)
			(end 0.12065 -0.3048)
			(stroke
				(width 0.1)
				(type default)
			)
			(layer "F.Fab")
		)
		(fp_line
			(start 0.12065 -0.3048)
			(end 0.67945 -0.3048)
			(stroke
				(width 0.1)
				(type default)
			)
			(layer "F.Fab")
		)
		(fp_line
			(start 0.120396 0.3048)
			(end 0.120396 0.2794)
			(stroke
				(width 0.1)
				(type default)
			)
			(layer "F.Fab")
		)
		(fp_line
			(start 0.120396 0.2794)
			(end -0.12065 0.2794)
			(stroke
				(width 0.1)
				(type default)
			)
			(layer "F.Fab")
		)
		(fp_line
			(start -0.12065 0.3048)
			(end -0.67945 0.3048)
			(stroke
				(width 0.1)
				(type default)
			)
			(layer "F.Fab")
		)
		(fp_line
			(start -0.12065 0.2794)
			(end -0.12065 0.3048)
			(stroke
				(width 0.1)
				(type default)
			)
			(layer "F.Fab")
		)
		(fp_line
			(start -0.12065 -0.2794)
			(end 0.12065 -0.2794)
			(stroke
				(width 0.1)
				(type default)
			)
			(layer "F.Fab")
		)
		(fp_line
			(start -0.12065 -0.305054)
			(end -0.12065 -0.2794)
			(stroke
				(width 0.1)
				(type default)
			)
			(layer "F.Fab")
		)
		(fp_line
			(start -0.67945 0.3048)
			(end -0.67945 -0.305054)
			(stroke
				(width 0.1)
				(type default)
			)
			(layer "F.Fab")
		)
		(fp_line
			(start -0.67945 -0.305054)
			(end -0.12065 -0.305054)
			(stroke
				(width 0.1)
				(type default)
			)
			(layer "F.Fab")
		)
		(pad "1" smd circle
			(at -0.40005 0 180)
			(size 0 0)
			(layers "F.Cu" "F.Mask" "F.Paste")
			(net "P3V3_AUX")
		)
		(pad "2" smd circle
			(at 0.40005 0 180)
			(size 0 0)
			(layers "F.Cu" "F.Mask" "F.Paste")
			(net "JTAG_SCM_TDI")
		)
	)
	(footprint ""
		(layer "F.Cu")
		(at 453.169782 -39.95674 90)
		(property "Reference" "R1486"
			(at 0 0 90)
			(layer "F.SilkS")
			(hide yes)
			(effects
				(font
					(size 1.27 1.27)
				)
			)
		)
		(property "Value" ""
			(at 0 0 90)
			(layer "F.Fab")
			(effects
				(font
					(size 1.27 1.27)
				)
			)
		)
		(duplicate_pad_numbers_are_jumpers no)
		(fp_line
			(start 0.7874 -0.4064)
			(end 0.7874 0.4064)
			(stroke
				(width 0.1524)
				(type default)
			)
			(layer "F.SilkS")
		)
		(fp_line
			(start -0.7874 -0.4064)
			(end 0.7874 -0.4064)
			(stroke
				(width 0.1524)
				(type default)
			)
			(layer "F.SilkS")
		)
		(fp_line
			(start 0.7874 0.4064)
			(end -0.7874 0.4064)
			(stroke
				(width 0.1524)
				(type default)
			)
			(layer "F.SilkS")
		)
		(fp_line
			(start -0.7874 0.4064)
			(end -0.7874 -0.4064)
			(stroke
				(width 0.1524)
				(type default)
			)
			(layer "F.SilkS")
		)
		(fp_line
			(start -0.12065 -0.305054)
			(end -0.12065 -0.2794)
			(stroke
				(width 0.1)
				(type default)
			)
			(layer "F.Fab")
		)
		(fp_line
			(start -0.67945 -0.305054)
			(end -0.12065 -0.305054)
			(stroke
				(width 0.1)
				(type default)
			)
			(layer "F.Fab")
		)
		(fp_line
			(start 0.67945 -0.3048)
			(end 0.67945 0.3048)
			(stroke
				(width 0.1)
				(type default)
			)
			(layer "F.Fab")
		)
		(fp_line
			(start 0.12065 -0.3048)
			(end 0.67945 -0.3048)
			(stroke
				(width 0.1)
				(type default)
			)
			(layer "F.Fab")
		)
		(fp_line
			(start 0.12065 -0.2794)
			(end 0.12065 -0.3048)
			(stroke
				(width 0.1)
				(type default)
			)
			(layer "F.Fab")
		)
		(fp_line
			(start -0.12065 -0.2794)
			(end 0.12065 -0.2794)
			(stroke
				(width 0.1)
				(type default)
			)
			(layer "F.Fab")
		)
		(fp_line
			(start 0.120396 0.2794)
			(end -0.12065 0.2794)
			(stroke
				(width 0.1)
				(type default)
			)
			(layer "F.Fab")
		)
		(fp_line
			(start -0.12065 0.2794)
			(end -0.12065 0.3048)
			(stroke
				(width 0.1)
				(type default)
			)
			(layer "F.Fab")
		)
		(fp_line
			(start 0.67945 0.3048)
			(end 0.120396 0.3048)
			(stroke
				(width 0.1)
				(type default)
			)
			(layer "F.Fab")
		)
		(fp_line
			(start 0.120396 0.3048)
			(end 0.120396 0.2794)
			(stroke
				(width 0.1)
				(type default)
			)
			(layer "F.Fab")
		)
		(fp_line
			(start -0.12065 0.3048)
			(end -0.67945 0.3048)
			(stroke
				(width 0.1)
				(type default)
			)
			(layer "F.Fab")
		)
		(fp_line
			(start -0.67945 0.3048)
			(end -0.67945 -0.305054)
			(stroke
				(width 0.1)
				(type default)
			)
			(layer "F.Fab")
		)
		(pad "1" smd circle
			(at -0.40005 0 90)
			(size 0 0)
			(layers "F.Cu" "F.Mask" "F.Paste")
			(net "P12V_OCP_SFF_BUF_EN_R")
		)
		(pad "2" smd circle
			(at 0.40005 0 90)
			(size 0 0)
			(layers "F.Cu" "F.Mask" "F.Paste")
			(net "P3V3_OCP_EN_1_R")
		)
	)
	(footprint ""
		(layer "F.Cu")
		(at 60.527438 -31.887922 -90)
		(property "Reference" "R3867"
			(at 0 0 270)
			(layer "F.SilkS")
			(hide yes)
			(effects
				(font
					(size 1.27 1.27)
				)
			)
		)
		(property "Value" ""
			(at 0 0 270)
			(layer "F.Fab")
			(effects
				(font
					(size 1.27 1.27)
				)
			)
		)
		(duplicate_pad_numbers_are_jumpers no)
		(fp_line
			(start -0.7874 0.4064)
			(end -0.7874 -0.4064)
			(stroke
				(width 0.1524)
				(type default)
			)
			(layer "F.SilkS")
		)
		(fp_line
			(start 0.7874 0.4064)
			(end -0.7874 0.4064)
			(stroke
				(width 0.1524)
				(type default)
			)
			(layer "F.SilkS")
		)
		(fp_line
			(start -0.7874 -0.4064)
			(end 0.7874 -0.4064)
			(stroke
				(width 0.1524)
				(type default)
			)
			(layer "F.SilkS")
		)
		(fp_line
			(start 0.7874 -0.4064)
			(end 0.7874 0.4064)
			(stroke
				(width 0.1524)
				(type default)
			)
			(layer "F.SilkS")
		)
		(fp_line
			(start -0.67945 0.3048)
			(end -0.67945 -0.305054)
			(stroke
				(width 0.1)
				(type default)
			)
			(layer "F.Fab")
		)
		(fp_line
			(start -0.12065 0.3048)
			(end -0.67945 0.3048)
			(stroke
				(width 0.1)
				(type default)
			)
			(layer "F.Fab")
		)
		(fp_line
			(start 0.120396 0.3048)
			(end 0.120396 0.2794)
			(stroke
				(width 0.1)
				(type default)
			)
			(layer "F.Fab")
		)
		(fp_line
			(start 0.67945 0.3048)
			(end 0.120396 0.3048)
			(stroke
				(width 0.1)
				(type default)
			)
			(layer "F.Fab")
		)
		(fp_line
			(start -0.12065 0.2794)
			(end -0.12065 0.3048)
			(stroke
				(width 0.1)
				(type default)
			)
			(layer "F.Fab")
		)
		(fp_line
			(start 0.120396 0.2794)
			(end -0.12065 0.2794)
			(stroke
				(width 0.1)
				(type default)
			)
			(layer "F.Fab")
		)
		(fp_line
			(start -0.12065 -0.2794)
			(end 0.12065 -0.2794)
			(stroke
				(width 0.1)
				(type default)
			)
			(layer "F.Fab")
		)
		(fp_line
			(start 0.12065 -0.2794)
			(end 0.12065 -0.3048)
			(stroke
				(width 0.1)
				(type default)
			)
			(layer "F.Fab")
		)
		(fp_line
			(start 0.12065 -0.3048)
			(end 0.67945 -0.3048)
			(stroke
				(width 0.1)
				(type default)
			)
			(layer "F.Fab")
		)
		(fp_line
			(start 0.67945 -0.3048)
			(end 0.67945 0.3048)
			(stroke
				(width 0.1)
				(type default)
			)
			(layer "F.Fab")
		)
		(fp_line
			(start -0.67945 -0.305054)
			(end -0.12065 -0.305054)
			(stroke
				(width 0.1)
				(type default)
			)
			(layer "F.Fab")
		)
		(fp_line
			(start -0.12065 -0.305054)
			(end -0.12065 -0.2794)
			(stroke
				(width 0.1)
				(type default)
			)
			(layer "F.Fab")
		)
		(pad "1" smd rect
			(at -0.40005 0 90)
			(size 0.4572 0.508)
			(layers "F.Cu" "F.Mask" "F.Paste")
			(net "P12V_OCP_SENSE_2")
		)
		(pad "2" smd rect
			(at 0.40005 0 90)
			(size 0.4572 0.508)
			(layers "F.Cu" "F.Mask" "F.Paste")
			(net "P12V_OCP_V3_2_ISENSE_MAM_MAM")
		)
	)
	(footprint ""
		(layer "F.Cu")
		(at 59.33313 -39.007034 90)
		(property "Reference" "R4060"
			(at 0 0 90)
			(layer "F.SilkS")
			(hide yes)
			(effects
				(font
					(size 1.27 1.27)
				)
			)
		)
		(property "Value" ""
			(at 0 0 90)
			(layer "F.Fab")
			(effects
				(font
					(size 1.27 1.27)
				)
			)
		)
		(duplicate_pad_numbers_are_jumpers no)
		(fp_line
			(start 0.7874 -0.4064)
			(end 0.7874 0.4064)
			(stroke
				(width 0.1524)
				(type default)
			)
			(layer "F.SilkS")
		)
		(fp_line
			(start -0.7874 -0.4064)
			(end 0.7874 -0.4064)
			(stroke
				(width 0.1524)
				(type default)
			)
			(layer "F.SilkS")
		)
		(fp_line
			(start 0.7874 0.4064)
			(end -0.7874 0.4064)
			(stroke
				(width 0.1524)
				(type default)
			)
			(layer "F.SilkS")
		)
		(fp_line
			(start -0.7874 0.4064)
			(end -0.7874 -0.4064)
			(stroke
				(width 0.1524)
				(type default)
			)
			(layer "F.SilkS")
		)
		(fp_line
			(start -0.12065 -0.305054)
			(end -0.12065 -0.2794)
			(stroke
				(width 0.1)
				(type default)
			)
			(layer "F.Fab")
		)
		(fp_line
			(start -0.67945 -0.305054)
			(end -0.12065 -0.305054)
			(stroke
				(width 0.1)
				(type default)
			)
			(layer "F.Fab")
		)
		(fp_line
			(start 0.67945 -0.3048)
			(end 0.67945 0.3048)
			(stroke
				(width 0.1)
				(type default)
			)
			(layer "F.Fab")
		)
		(fp_line
			(start 0.12065 -0.3048)
			(end 0.67945 -0.3048)
			(stroke
				(width 0.1)
				(type default)
			)
			(layer "F.Fab")
		)
		(fp_line
			(start 0.12065 -0.2794)
			(end 0.12065 -0.3048)
			(stroke
				(width 0.1)
				(type default)
			)
			(layer "F.Fab")
		)
		(fp_line
			(start -0.12065 -0.2794)
			(end 0.12065 -0.2794)
			(stroke
				(width 0.1)
				(type default)
			)
			(layer "F.Fab")
		)
		(fp_line
			(start 0.120396 0.2794)
			(end -0.12065 0.2794)
			(stroke
				(width 0.1)
				(type default)
			)
			(layer "F.Fab")
		)
		(fp_line
			(start -0.12065 0.2794)
			(end -0.12065 0.3048)
			(stroke
				(width 0.1)
				(type default)
			)
			(layer "F.Fab")
		)
		(fp_line
			(start 0.67945 0.3048)
			(end 0.120396 0.3048)
			(stroke
				(width 0.1)
				(type default)
			)
			(layer "F.Fab")
		)
		(fp_line
			(start 0.120396 0.3048)
			(end 0.120396 0.2794)
			(stroke
				(width 0.1)
				(type default)
			)
			(layer "F.Fab")
		)
		(fp_line
			(start -0.12065 0.3048)
			(end -0.67945 0.3048)
			(stroke
				(width 0.1)
				(type default)
			)
			(layer "F.Fab")
		)
		(fp_line
			(start -0.67945 0.3048)
			(end -0.67945 -0.305054)
			(stroke
				(width 0.1)
				(type default)
			)
			(layer "F.Fab")
		)
		(pad "1" smd circle
			(at -0.40005 0 90)
			(size 0 0)
			(layers "F.Cu" "F.Mask" "F.Paste")
			(net "P3V3_OCP_V3_2_EN_R")
		)
		(pad "2" smd circle
			(at 0.40005 0 90)
			(size 0 0)
			(layers "F.Cu" "F.Mask" "F.Paste")
			(net "P3V3_OCP_EN_2_R")
		)
	)
	(footprint ""
		(layer "F.Cu")
		(at 302.256698 -118.179088 180)
		(property "Reference" "R718"
			(at 0 0 180)
			(layer "F.SilkS")
			(hide yes)
			(effects
				(font
					(size 1.27 1.27)
				)
			)
		)
		(property "Value" ""
			(at 0 0 180)
			(layer "F.Fab")
			(effects
				(font
					(size 1.27 1.27)
				)
			)
		)
		(duplicate_pad_numbers_are_jumpers no)
		(fp_line
			(start 0.7874 0.4064)
			(end -0.7874 0.4064)
			(stroke
				(width 0.1524)
				(type default)
			)
			(layer "F.SilkS")
		)
		(fp_line
			(start 0.7874 -0.4064)
			(end 0.7874 0.4064)
			(stroke
				(width 0.1524)
				(type default)
			)
			(layer "F.SilkS")
		)
		(fp_line
			(start -0.7874 0.4064)
			(end -0.7874 -0.4064)
			(stroke
				(width 0.1524)
				(type default)
			)
			(layer "F.SilkS")
		)
		(fp_line
			(start -0.7874 -0.4064)
			(end 0.7874 -0.4064)
			(stroke
				(width 0.1524)
				(type default)
			)
			(layer "F.SilkS")
		)
		(fp_line
			(start 0.67945 0.3048)
			(end 0.120396 0.3048)
			(stroke
				(width 0.1)
				(type default)
			)
			(layer "F.Fab")
		)
		(fp_line
			(start 0.67945 -0.3048)
			(end 0.67945 0.3048)
			(stroke
				(width 0.1)
				(type default)
			)
			(layer "F.Fab")
		)
		(fp_line
			(start 0.12065 -0.2794)
			(end 0.12065 -0.3048)
			(stroke
				(width 0.1)
				(type default)
			)
			(layer "F.Fab")
		)
		(fp_line
			(start 0.12065 -0.3048)
			(end 0.67945 -0.3048)
			(stroke
				(width 0.1)
				(type default)
			)
			(layer "F.Fab")
		)
		(fp_line
			(start 0.120396 0.3048)
			(end 0.120396 0.2794)
			(stroke
				(width 0.1)
				(type default)
			)
			(layer "F.Fab")
		)
		(fp_line
			(start 0.120396 0.2794)
			(end -0.12065 0.2794)
			(stroke
				(width 0.1)
				(type default)
			)
			(layer "F.Fab")
		)
		(fp_line
			(start -0.12065 0.3048)
			(end -0.67945 0.3048)
			(stroke
				(width 0.1)
				(type default)
			)
			(layer "F.Fab")
		)
		(fp_line
			(start -0.12065 0.2794)
			(end -0.12065 0.3048)
			(stroke
				(width 0.1)
				(type default)
			)
			(layer "F.Fab")
		)
		(fp_line
			(start -0.12065 -0.2794)
			(end 0.12065 -0.2794)
			(stroke
				(width 0.1)
				(type default)
			)
			(layer "F.Fab")
		)
		(fp_line
			(start -0.12065 -0.305054)
			(end -0.12065 -0.2794)
			(stroke
				(width 0.1)
				(type default)
			)
			(layer "F.Fab")
		)
		(fp_line
			(start -0.67945 0.3048)
			(end -0.67945 -0.305054)
			(stroke
				(width 0.1)
				(type default)
			)
			(layer "F.Fab")
		)
		(fp_line
			(start -0.67945 -0.305054)
			(end -0.12065 -0.305054)
			(stroke
				(width 0.1)
				(type default)
			)
			(layer "F.Fab")
		)
		(pad "1" smd circle
			(at -0.40005 0 180)
			(size 0 0)
			(layers "F.Cu" "F.Mask" "F.Paste")
			(net "MB_FRU_ADDR1")
		)
		(pad "2" smd circle
			(at 0.40005 0 180)
			(size 0 0)
			(layers "F.Cu" "F.Mask" "F.Paste")
			(net "GND")
		)
	)
	(footprint ""
		(layer "F.Cu")
		(at 323.637148 -44.716954 180)
		(property "Reference" "R3862"
			(at 0 0 180)
			(layer "F.SilkS")
			(hide yes)
			(effects
				(font
					(size 1.27 1.27)
				)
			)
		)
		(property "Value" ""
			(at 0 0 180)
			(layer "F.Fab")
			(effects
				(font
					(size 1.27 1.27)
				)
			)
		)
		(duplicate_pad_numbers_are_jumpers no)
		(fp_line
			(start 0.7874 0.4064)
			(end -0.7874 0.4064)
			(stroke
				(width 0.1524)
				(type default)
			)
			(layer "F.SilkS")
		)
		(fp_line
			(start 0.7874 -0.4064)
			(end 0.7874 0.4064)
			(stroke
				(width 0.1524)
				(type default)
			)
			(layer "F.SilkS")
		)
		(fp_line
			(start -0.7874 0.4064)
			(end -0.7874 -0.4064)
			(stroke
				(width 0.1524)
				(type default)
			)
			(layer "F.SilkS")
		)
		(fp_line
			(start -0.7874 -0.4064)
			(end 0.7874 -0.4064)
			(stroke
				(width 0.1524)
				(type default)
			)
			(layer "F.SilkS")
		)
		(fp_line
			(start 0.67945 0.3048)
			(end 0.120396 0.3048)
			(stroke
				(width 0.1)
				(type default)
			)
			(layer "F.Fab")
		)
		(fp_line
			(start 0.67945 -0.3048)
			(end 0.67945 0.3048)
			(stroke
				(width 0.1)
				(type default)
			)
			(layer "F.Fab")
		)
		(fp_line
			(start 0.12065 -0.2794)
			(end 0.12065 -0.3048)
			(stroke
				(width 0.1)
				(type default)
			)
			(layer "F.Fab")
		)
		(fp_line
			(start 0.12065 -0.3048)
			(end 0.67945 -0.3048)
			(stroke
				(width 0.1)
				(type default)
			)
			(layer "F.Fab")
		)
		(fp_line
			(start 0.120396 0.3048)
			(end 0.120396 0.2794)
			(stroke
				(width 0.1)
				(type default)
			)
			(layer "F.Fab")
		)
		(fp_line
			(start 0.120396 0.2794)
			(end -0.12065 0.2794)
			(stroke
				(width 0.1)
				(type default)
			)
			(layer "F.Fab")
		)
		(fp_line
			(start -0.12065 0.3048)
			(end -0.67945 0.3048)
			(stroke
				(width 0.1)
				(type default)
			)
			(layer "F.Fab")
		)
		(fp_line
			(start -0.12065 0.2794)
			(end -0.12065 0.3048)
			(stroke
				(width 0.1)
				(type default)
			)
			(layer "F.Fab")
		)
		(fp_line
			(start -0.12065 -0.2794)
			(end 0.12065 -0.2794)
			(stroke
				(width 0.1)
				(type default)
			)
			(layer "F.Fab")
		)
		(fp_line
			(start -0.12065 -0.305054)
			(end -0.12065 -0.2794)
			(stroke
				(width 0.1)
				(type default)
			)
			(layer "F.Fab")
		)
		(fp_line
			(start -0.67945 0.3048)
			(end -0.67945 -0.305054)
			(stroke
				(width 0.1)
				(type default)
			)
			(layer "F.Fab")
		)
		(fp_line
			(start -0.67945 -0.305054)
			(end -0.12065 -0.305054)
			(stroke
				(width 0.1)
				(type default)
			)
			(layer "F.Fab")
		)
		(pad "1" smd rect
			(at -0.40005 0)
			(size 0.4572 0.508)
			(layers "F.Cu" "F.Mask" "F.Paste")
			(net "P12V_OCP_V3_2_ISENSE_MPS_TIC")
		)
		(pad "2" smd rect
			(at 0.40005 0)
			(size 0.4572 0.508)
			(layers "F.Cu" "F.Mask" "F.Paste")
			(net "P12V_OCP_V3_2_ISENSE_TIC")
		)
	)
	(footprint ""
		(layer "F.Cu")
		(at 322.027296 -378.95403 -90)
		(property "Reference" "C908"
			(at 0 0 270)
			(layer "F.SilkS")
			(hide yes)
			(effects
				(font
					(size 1.27 1.27)
				)
			)
		)
		(property "Value" ""
			(at 0 0 270)
			(layer "F.Fab")
			(effects
				(font
					(size 1.27 1.27)
				)
			)
		)
		(duplicate_pad_numbers_are_jumpers no)
		(fp_line
			(start -0.299974 0.150114)
			(end -0.299974 -0.150114)
			(stroke
				(width 0.1)
				(type default)
			)
			(layer "F.Fab")
		)
		(fp_line
			(start 0.299974 0.150114)
			(end -0.299974 0.150114)
			(stroke
				(width 0.1)
				(type default)
			)
			(layer "F.Fab")
		)
		(fp_line
			(start -0.299974 -0.150114)
			(end 0.299974 -0.150114)
			(stroke
				(width 0.1)
				(type default)
			)
			(layer "F.Fab")
		)
		(fp_line
			(start 0.299974 -0.150114)
			(end 0.299974 0.150114)
			(stroke
				(width 0.1)
				(type default)
			)
			(layer "F.Fab")
		)
		(pad "1" smd rect
			(at -0.2667 0 270)
			(size 0.3048 0.381)
			(layers "F.Cu" "F.Mask" "F.Paste")
			(net "P5E_CPU0_P0_TX_C_DN<12>")
		)
		(pad "2" smd rect
			(at 0.2667 0 270)
			(size 0.3048 0.381)
			(layers "F.Cu" "F.Mask" "F.Paste")
			(net "P5E_CPU0_P0_TX_DN<12>")
		)
	)
)
